# S9S_MB_2U (Grand Teton) — schematic netlist excerpt (pin names and nets, part order shuffled) for the footprints in the layout excerpt that follows; sources: Cadence DE-HDL packaged netlist, KiCad conversion of 03242023_DA0F0TMBIJ0_F0T_Motherboard_J_brd_V01_OCP.brd

R4297  Q_RES  100 1% CHIP  pkg 0402LF  page 124 : A = PWRGD_DRAMPWRGD_CPU0_EF_LVC1_R2 ; B = PWRGD_DRAMPWRGD_CPU0_EF_LVC1_R
C2259  Q_CAP  0.1UF 25V 10% X7R  pkg 0402  page 212 : A = VFG_3P3A_CLK_GEN ; B = GND

(kicad_pcb
	(version 20260206)
	(generator "pcbnew")
	(generator_version "10.0")
	(general
		(thickness 1.6)
		(legacy_teardrops no)
	)
	(paper "A4")
	(title_block
		(title "03242023_DA0F0TMBIJ0_F0T_Motherboard_J_brd_V01_OCP.brd")
		(comment 1 "Grand Teton / footprints 5286-5287 of 6105")
	)
	(layers
		(0 "F.Cu" signal "TOP")
		(4 "In1.Cu" signal "GND")
		(6 "In2.Cu" signal "IN1")
		(8 "In3.Cu" signal "GND1")
		(10 "In4.Cu" signal "IN2")
		(12 "In5.Cu" signal "GND2")
		(14 "In6.Cu" signal "IN3")
		(16 "In7.Cu" signal "GND3")
		(18 "In8.Cu" signal "VCC")
		(20 "In9.Cu" signal "VCC1")
		(22 "In10.Cu" signal "GND4")
		(24 "In11.Cu" signal "IN4")
		(26 "In12.Cu" signal "GND5")
		(28 "In13.Cu" signal "IN5")
		(30 "In14.Cu" signal "GND6")
		(32 "In15.Cu" signal "IN6")
		(34 "In16.Cu" signal "GND7")
		(2 "B.Cu" signal "BOTTOM")
		(9 "F.Adhes" user "F.Adhesive")
		(11 "B.Adhes" user "B.Adhesive")
		(13 "F.Paste" user "Package Geometry/Pastemask Top")
		(15 "B.Paste" user "Package Geometry/Pastemask Bottom")
		(5 "F.SilkS" user "Ref Des/Silkscreen Top")
		(7 "B.SilkS" user "Ref Des/Silkscreen Bottom")
		(1 "F.Mask" user "Board Geometry/Soldermask Top")
		(3 "B.Mask" user "Board Geometry/Soldermask Bottom")
		(17 "Dwgs.User" user "User.Drawings")
		(19 "Cmts.User" user "User.Comments")
		(21 "Eco1.User" user "User.Eco1")
		(23 "Eco2.User" user "User.Eco2")
		(25 "Edge.Cuts" user "Board Geometry/Outline")
		(27 "Margin" user)
		(31 "F.CrtYd" user "Package Geometry/Place Bound Top")
		(29 "B.CrtYd" user "Package Geometry/Place Bound Bottom")
		(35 "F.Fab" user "Ref Des/Assembly Top")
		(33 "B.Fab" user "Ref Des/Assembly Bottom")
	)
	(footprint ""
		(layer "B.Cu")
		(at 233.9086 -250.505468 180)
		(property "Reference" "C2259"
			(at 0 0 0)
			(layer "B.SilkS")
			(hide yes)
			(effects
				(font
					(size 1.27 1.27)
				)
				(justify mirror)
			)
		)
		(property "Value" ""
			(at 0 0 0)
			(layer "B.Fab")
			(effects
				(font
					(size 1.27 1.27)
				)
				(justify mirror)
			)
		)
		(duplicate_pad_numbers_are_jumpers no)
		(fp_line
			(start 0.7874 0.4064)
			(end 0.7874 -0.4064)
			(stroke
				(width 0.1524)
				(type default)
			)
			(layer "B.SilkS")
		)
		(fp_line
			(start 0.7874 -0.4064)
			(end -0.7874 -0.4064)
			(stroke
				(width 0.1524)
				(type default)
			)
			(layer "B.SilkS")
		)
		(fp_line
			(start -0.7874 0.4064)
			(end 0.7874 0.4064)
			(stroke
				(width 0.1524)
				(type default)
			)
			(layer "B.SilkS")
		)
		(fp_line
			(start -0.7874 -0.4064)
			(end -0.7874 0.4064)
			(stroke
				(width 0.1524)
				(type default)
			)
			(layer "B.SilkS")
		)
		(fp_line
			(start 0.67945 0.3048)
			(end 0.67945 -0.305054)
			(stroke
				(width 0.1)
				(type default)
			)
			(layer "B.Fab")
		)
		(fp_line
			(start 0.67945 -0.305054)
			(end 0.12065 -0.305054)
			(stroke
				(width 0.1)
				(type default)
			)
			(layer "B.Fab")
		)
		(fp_line
			(start 0.12065 0.3048)
			(end 0.67945 0.3048)
			(stroke
				(width 0.1)
				(type default)
			)
			(layer "B.Fab")
		)
		(fp_line
			(start 0.12065 0.2794)
			(end 0.12065 0.3048)
			(stroke
				(width 0.1)
				(type default)
			)
			(layer "B.Fab")
		)
		(fp_line
			(start 0.12065 -0.2794)
			(end -0.12065 -0.2794)
			(stroke
				(width 0.1)
				(type default)
			)
			(layer "B.Fab")
		)
		(fp_line
			(start 0.12065 -0.305054)
			(end 0.12065 -0.2794)
			(stroke
				(width 0.1)
				(type default)
			)
			(layer "B.Fab")
		)
		(fp_line
			(start -0.120396 0.3048)
			(end -0.120396 0.2794)
			(stroke
				(width 0.1)
				(type default)
			)
			(layer "B.Fab")
		)
		(fp_line
			(start -0.120396 0.2794)
			(end 0.12065 0.2794)
			(stroke
				(width 0.1)
				(type default)
			)
			(layer "B.Fab")
		)
		(fp_line
			(start -0.12065 -0.2794)
			(end -0.12065 -0.3048)
			(stroke
				(width 0.1)
				(type default)
			)
			(layer "B.Fab")
		)
		(fp_line
			(start -0.12065 -0.3048)
			(end -0.67945 -0.3048)
			(stroke
				(width 0.1)
				(type default)
			)
			(layer "B.Fab")
		)
		(fp_line
			(start -0.67945 0.3048)
			(end -0.120396 0.3048)
			(stroke
				(width 0.1)
				(type default)
			)
			(layer "B.Fab")
		)
		(fp_line
			(start -0.67945 -0.3048)
			(end -0.67945 0.3048)
			(stroke
				(width 0.1)
				(type default)
			)
			(layer "B.Fab")
		)
		(pad "1" smd circle
			(at 0.40005 0)
			(size 0 0)
			(layers "B.Cu" "B.Mask" "B.Paste")
			(net "VFG_3P3A_CLK_GEN")
		)
		(pad "2" smd circle
			(at -0.40005 0)
			(size 0 0)
			(layers "B.Cu" "B.Mask" "B.Paste")
			(net "GND")
		)
	)
	(footprint ""
		(layer "B.Cu")
		(at 401.828 -192.623948 -90)
		(property "Reference" "R4297"
			(at 0 0 90)
			(layer "B.SilkS")
			(hide yes)
			(effects
				(font
					(size 1.27 1.27)
				)
				(justify mirror)
			)
		)
		(property "Value" ""
			(at 0 0 90)
			(layer "B.Fab")
			(effects
				(font
					(size 1.27 1.27)
				)
				(justify mirror)
			)
		)
		(duplicate_pad_numbers_are_jumpers no)
		(fp_line
			(start -0.7874 0.4064)
			(end 0.7874 0.4064)
			(stroke
				(width 0.1524)
				(type default)
			)
			(layer "B.SilkS")
		)
		(fp_line
			(start 0.7874 0.4064)
			(end 0.7874 -0.4064)
			(stroke
				(width 0.1524)
				(type default)
			)
			(layer "B.SilkS")
		)
		(fp_line
			(start -0.7874 -0.4064)
			(end -0.7874 0.4064)
			(stroke
				(width 0.1524)
				(type default)
			)
			(layer "B.SilkS")
		)
		(fp_line
			(start 0.7874 -0.4064)
			(end -0.7874 -0.4064)
			(stroke
				(width 0.1524)
				(type default)
			)
			(layer "B.SilkS")
		)
		(fp_line
			(start -0.67945 0.3048)
			(end -0.120396 0.3048)
			(stroke
				(width 0.1)
				(type default)
			)
			(layer "B.Fab")
		)
		(fp_line
			(start -0.120396 0.3048)
			(end -0.120396 0.2794)
			(stroke
				(width 0.1)
				(type default)
			)
			(layer "B.Fab")
		)
		(fp_line
			(start 0.12065 0.3048)
			(end 0.67945 0.3048)
			(stroke
				(width 0.1)
				(type default)
			)
			(layer "B.Fab")
		)
		(fp_line
			(start 0.67945 0.3048)
			(end 0.67945 -0.305054)
			(stroke
				(width 0.1)
				(type default)
			)
			(layer "B.Fab")
		)
		(fp_line
			(start -0.120396 0.2794)
			(end 0.12065 0.2794)
			(stroke
				(width 0.1)
				(type default)
			)
			(layer "B.Fab")
		)
		(fp_line
			(start 0.12065 0.2794)
			(end 0.12065 0.3048)
			(stroke
				(width 0.1)
				(type default)
			)
			(layer "B.Fab")
		)
		(fp_line
			(start -0.12065 -0.2794)
			(end -0.12065 -0.3048)
			(stroke
				(width 0.1)
				(type default)
			)
			(layer "B.Fab")
		)
		(fp_line
			(start 0.12065 -0.2794)
			(end -0.12065 -0.2794)
			(stroke
				(width 0.1)
				(type default)
			)
			(layer "B.Fab")
		)
		(fp_line
			(start -0.67945 -0.3048)
			(end -0.67945 0.3048)
			(stroke
				(width 0.1)
				(type default)
			)
			(layer "B.Fab")
		)
		(fp_line
			(start -0.12065 -0.3048)
			(end -0.67945 -0.3048)
			(stroke
				(width 0.1)
				(type default)
			)
			(layer "B.Fab")
		)
		(fp_line
			(start 0.12065 -0.305054)
			(end 0.12065 -0.2794)
			(stroke
				(width 0.1)
				(type default)
			)
			(layer "B.Fab")
		)
		(fp_line
			(start 0.67945 -0.305054)
			(end 0.12065 -0.305054)
			(stroke
				(width 0.1)
				(type default)
			)
			(layer "B.Fab")
		)
		(pad "1" smd circle
			(at 0.40005 0 90)
			(size 0 0)
			(layers "B.Cu" "B.Mask" "B.Paste")
			(net "PWRGD_DRAMPWRGD_CPU0_EF_LVC1_R2")
		)
		(pad "2" smd circle
			(at -0.40005 0 90)
			(size 0 0)
			(layers "B.Cu" "B.Mask" "B.Paste")
			(net "PWRGD_DRAMPWRGD_CPU0_EF_LVC1_R")
		)
	)
)
